(kicad_pcb
	(version 20260206)
	(generator "pcbnew")
	(generator_version "10.0")
	(general
		(thickness 1.6)
		(legacy_teardrops no)
	)
	(paper "A4")
	(title_block
		(title "9052_F0T_PDB_Converter_Brick_F_V03_1208_1600_OCP.brd")
		(comment 1 "Grand Teton / footprints 217-223 of 578")
	)
	(layers
		(0 "F.Cu" signal "TOP")
		(4 "In1.Cu" signal "GND")
		(6 "In2.Cu" signal "IN1")
		(8 "In3.Cu" signal "GND1")
		(10 "In4.Cu" signal "VCC")
		(12 "In5.Cu" signal "VCC1")
		(14 "In6.Cu" signal "GND2")
		(16 "In7.Cu" signal "IN2")
		(18 "In8.Cu" signal "GND3")
		(2 "B.Cu" signal "BOTTOM")
		(9 "F.Adhes" user "F.Adhesive")
		(11 "B.Adhes" user "B.Adhesive")
		(13 "F.Paste" user "Package Geometry/Pastemask Top")
		(15 "B.Paste" user "Package Geometry/Pastemask Bottom")
		(5 "F.SilkS" user "Ref Des/Silkscreen Top")
		(7 "B.SilkS" user "Ref Des/Silkscreen Bottom")
		(1 "F.Mask" user "Board Geometry/Soldermask Top")
		(3 "B.Mask" user "Board Geometry/Soldermask Bottom")
		(17 "Dwgs.User" user "User.Drawings")
		(19 "Cmts.User" user "User.Comments")
		(21 "Eco1.User" user "User.Eco1")
		(23 "Eco2.User" user "User.Eco2")
		(25 "Edge.Cuts" user "Board Geometry/Outline")
		(27 "Margin" user)
		(31 "F.CrtYd" user "Package Geometry/Place Bound Top")
		(29 "B.CrtYd" user "Package Geometry/Place Bound Bottom")
		(35 "F.Fab" user "Ref Des/Assembly Top")
		(33 "B.Fab" user "Ref Des/Assembly Bottom")
	)
	(footprint ""
		(layer "F.Cu")
		(at 179.324 -14.732 90)
		(property "Reference" "PR88"
			(at 0 0 90)
			(layer "F.SilkS")
			(hide yes)
			(effects
				(font
					(size 1.27 1.27)
				)
			)
		)
		(property "Value" ""
			(at 0 0 90)
			(layer "F.Fab")
			(effects
				(font
					(size 1.27 1.27)
				)
			)
		)
		(duplicate_pad_numbers_are_jumpers no)
		(fp_line
			(start 0.7874 -0.4064)
			(end 0.7874 0.4064)
			(stroke
				(width 0.1524)
				(type default)
			)
			(layer "F.SilkS")
		)
		(fp_line
			(start -0.7874 -0.4064)
			(end 0.7874 -0.4064)
			(stroke
				(width 0.1524)
				(type default)
			)
			(layer "F.SilkS")
		)
		(fp_line
			(start 0.7874 0.4064)
			(end -0.7874 0.4064)
			(stroke
				(width 0.1524)
				(type default)
			)
			(layer "F.SilkS")
		)
		(fp_line
			(start -0.7874 0.4064)
			(end -0.7874 -0.4064)
			(stroke
				(width 0.1524)
				(type default)
			)
			(layer "F.SilkS")
		)
		(fp_line
			(start -0.12065 -0.305054)
			(end -0.12065 -0.2794)
			(stroke
				(width 0.1)
				(type default)
			)
			(layer "F.Fab")
		)
		(fp_line
			(start -0.67945 -0.305054)
			(end -0.12065 -0.305054)
			(stroke
				(width 0.1)
				(type default)
			)
			(layer "F.Fab")
		)
		(fp_line
			(start 0.67945 -0.3048)
			(end 0.67945 0.3048)
			(stroke
				(width 0.1)
				(type default)
			)
			(layer "F.Fab")
		)
		(fp_line
			(start 0.12065 -0.3048)
			(end 0.67945 -0.3048)
			(stroke
				(width 0.1)
				(type default)
			)
			(layer "F.Fab")
		)
		(fp_line
			(start 0.12065 -0.2794)
			(end 0.12065 -0.3048)
			(stroke
				(width 0.1)
				(type default)
			)
			(layer "F.Fab")
		)
		(fp_line
			(start -0.12065 -0.2794)
			(end 0.12065 -0.2794)
			(stroke
				(width 0.1)
				(type default)
			)
			(layer "F.Fab")
		)
		(fp_line
			(start 0.120396 0.2794)
			(end -0.12065 0.2794)
			(stroke
				(width 0.1)
				(type default)
			)
			(layer "F.Fab")
		)
		(fp_line
			(start -0.12065 0.2794)
			(end -0.12065 0.3048)
			(stroke
				(width 0.1)
				(type default)
			)
			(layer "F.Fab")
		)
		(fp_line
			(start 0.67945 0.3048)
			(end 0.120396 0.3048)
			(stroke
				(width 0.1)
				(type default)
			)
			(layer "F.Fab")
		)
		(fp_line
			(start 0.120396 0.3048)
			(end 0.120396 0.2794)
			(stroke
				(width 0.1)
				(type default)
			)
			(layer "F.Fab")
		)
		(fp_line
			(start -0.12065 0.3048)
			(end -0.67945 0.3048)
			(stroke
				(width 0.1)
				(type default)
			)
			(layer "F.Fab")
		)
		(fp_line
			(start -0.67945 0.3048)
			(end -0.67945 -0.305054)
			(stroke
				(width 0.1)
				(type default)
			)
			(layer "F.Fab")
		)
		(pad "1" smd circle
			(at -0.40005 0 90)
			(size 0 0)
			(layers "F.Cu" "F.Mask" "F.Paste")
			(net "P3V3_AUX_MODE")
		)
		(pad "2" smd circle
			(at 0.40005 0 90)
			(size 0 0)
			(layers "F.Cu" "F.Mask" "F.Paste")
			(net "GND")
		)
	)
	(footprint ""
		(layer "F.Cu")
		(at 176.79289 -9.32053)
		(property "Reference" "PR91"
			(at 0 0 0)
			(layer "F.SilkS")
			(hide yes)
			(effects
				(font
					(size 1.27 1.27)
				)
			)
		)
		(property "Value" ""
			(at 0 0 0)
			(layer "F.Fab")
			(effects
				(font
					(size 1.27 1.27)
				)
			)
		)
		(duplicate_pad_numbers_are_jumpers no)
		(fp_line
			(start -0.7874 -0.4064)
			(end 0.7874 -0.4064)
			(stroke
				(width 0.1524)
				(type default)
			)
			(layer "F.SilkS")
		)
		(fp_line
			(start -0.7874 0.4064)
			(end -0.7874 -0.4064)
			(stroke
				(width 0.1524)
				(type default)
			)
			(layer "F.SilkS")
		)
		(fp_line
			(start 0.7874 -0.4064)
			(end 0.7874 0.4064)
			(stroke
				(width 0.1524)
				(type default)
			)
			(layer "F.SilkS")
		)
		(fp_line
			(start 0.7874 0.4064)
			(end -0.7874 0.4064)
			(stroke
				(width 0.1524)
				(type default)
			)
			(layer "F.SilkS")
		)
		(fp_line
			(start -0.67945 -0.305054)
			(end -0.12065 -0.305054)
			(stroke
				(width 0.1)
				(type default)
			)
			(layer "F.Fab")
		)
		(fp_line
			(start -0.67945 0.3048)
			(end -0.67945 -0.305054)
			(stroke
				(width 0.1)
				(type default)
			)
			(layer "F.Fab")
		)
		(fp_line
			(start -0.12065 -0.305054)
			(end -0.12065 -0.2794)
			(stroke
				(width 0.1)
				(type default)
			)
			(layer "F.Fab")
		)
		(fp_line
			(start -0.12065 -0.2794)
			(end 0.12065 -0.2794)
			(stroke
				(width 0.1)
				(type default)
			)
			(layer "F.Fab")
		)
		(fp_line
			(start -0.12065 0.2794)
			(end -0.12065 0.3048)
			(stroke
				(width 0.1)
				(type default)
			)
			(layer "F.Fab")
		)
		(fp_line
			(start -0.12065 0.3048)
			(end -0.67945 0.3048)
			(stroke
				(width 0.1)
				(type default)
			)
			(layer "F.Fab")
		)
		(fp_line
			(start 0.120396 0.2794)
			(end -0.12065 0.2794)
			(stroke
				(width 0.1)
				(type default)
			)
			(layer "F.Fab")
		)
		(fp_line
			(start 0.120396 0.3048)
			(end 0.120396 0.2794)
			(stroke
				(width 0.1)
				(type default)
			)
			(layer "F.Fab")
		)
		(fp_line
			(start 0.12065 -0.3048)
			(end 0.67945 -0.3048)
			(stroke
				(width 0.1)
				(type default)
			)
			(layer "F.Fab")
		)
		(fp_line
			(start 0.12065 -0.2794)
			(end 0.12065 -0.3048)
			(stroke
				(width 0.1)
				(type default)
			)
			(layer "F.Fab")
		)
		(fp_line
			(start 0.67945 -0.3048)
			(end 0.67945 0.3048)
			(stroke
				(width 0.1)
				(type default)
			)
			(layer "F.Fab")
		)
		(fp_line
			(start 0.67945 0.3048)
			(end 0.120396 0.3048)
			(stroke
				(width 0.1)
				(type default)
			)
			(layer "F.Fab")
		)
		(pad "1" smd circle
			(at -0.40005 0)
			(size 0 0)
			(layers "F.Cu" "F.Mask" "F.Paste")
			(net "P3V3_AUX_FB")
		)
		(pad "2" smd circle
			(at 0.40005 0)
			(size 0 0)
			(layers "F.Cu" "F.Mask" "F.Paste")
			(net "GND")
		)
	)
	(footprint ""
		(layer "F.Cu")
		(at 251.079 -57.912 -90)
		(property "Reference" "H14"
			(at -6.429502 12.066016 0)
			(unlocked yes)
			(layer "F.SilkS")
			(effects
				(font
					(size 0.7874 0.5842)
					(thickness 0.1524)
				)
				(justify left)
			)
		)
		(property "Value" ""
			(at 0 0 270)
			(layer "F.Fab")
			(effects
				(font
					(size 1.27 1.27)
				)
			)
		)
		(duplicate_pad_numbers_are_jumpers no)
		(pad "1" thru_hole oval
			(at 0 0 270)
			(size 10.0076 32.004)
			(drill 3.0226
				(offset 0 10.999978)
			)
			(layers "*.Cu" "*.Mask")
			(remove_unused_layers no)
			(net "GND")
			(clearance -1.995678)
			(padstack
				(mode front_inner_back)
				(layer "Inner"
					(shape circle)
					(size 0 0)
					(clearance 0)
				)
				(layer "B.Cu"
					(shape oval)
					(size 10.0076 32.004)
					(offset 0 10.999978)
					(clearance -1.995678)
				)
			)
		)
	)
	(footprint ""
		(layer "F.Cu")
		(at 292.757098 -34.396172 90)
		(property "Reference" "PR32"
			(at 0 0 90)
			(layer "F.SilkS")
			(hide yes)
			(effects
				(font
					(size 1.27 1.27)
				)
			)
		)
		(property "Value" ""
			(at 0 0 90)
			(layer "F.Fab")
			(effects
				(font
					(size 1.27 1.27)
				)
			)
		)
		(duplicate_pad_numbers_are_jumpers no)
		(fp_line
			(start 1.651 -0.8382)
			(end 1.651 0.8382)
			(stroke
				(width 0.1524)
				(type default)
			)
			(layer "F.SilkS")
		)
		(fp_line
			(start -1.651 -0.8382)
			(end 1.651 -0.8382)
			(stroke
				(width 0.1524)
				(type default)
			)
			(layer "F.SilkS")
		)
		(fp_line
			(start 1.651 0.8382)
			(end -1.651 0.8382)
			(stroke
				(width 0.1524)
				(type default)
			)
			(layer "F.SilkS")
		)
		(fp_line
			(start -1.651 0.8382)
			(end -1.651 -0.8382)
			(stroke
				(width 0.1524)
				(type default)
			)
			(layer "F.SilkS")
		)
		(fp_line
			(start 1.560576 -0.7366)
			(end 1.524 -0.7366)
			(stroke
				(width 0.1)
				(type default)
			)
			(layer "F.Fab")
		)
		(fp_line
			(start 1.524 -0.7366)
			(end -1.524 -0.7366)
			(stroke
				(width 0.1)
				(type default)
			)
			(layer "F.Fab")
		)
		(fp_line
			(start -1.524 -0.7366)
			(end -1.559814 -0.7366)
			(stroke
				(width 0.1)
				(type default)
			)
			(layer "F.Fab")
		)
		(fp_line
			(start -1.559814 -0.7366)
			(end -1.559814 0.7366)
			(stroke
				(width 0.1)
				(type default)
			)
			(layer "F.Fab")
		)
		(fp_line
			(start 1.560576 0.7366)
			(end 1.560576 -0.7366)
			(stroke
				(width 0.1)
				(type default)
			)
			(layer "F.Fab")
		)
		(fp_line
			(start 1.524 0.7366)
			(end 1.560576 0.7366)
			(stroke
				(width 0.1)
				(type default)
			)
			(layer "F.Fab")
		)
		(fp_line
			(start -1.524 0.7366)
			(end 1.524 0.7366)
			(stroke
				(width 0.1)
				(type default)
			)
			(layer "F.Fab")
		)
		(fp_line
			(start -1.559814 0.7366)
			(end -1.524 0.7366)
			(stroke
				(width 0.1)
				(type default)
			)
			(layer "F.Fab")
		)
		(pad "1" smd rect
			(at -0.94996 0 270)
			(size 1.1176 1.3716)
			(layers "F.Cu" "F.Mask" "F.Paste")
			(net "P52V_HS1_DV_DT_R")
		)
		(pad "2" smd rect
			(at 0.94996 0 270)
			(size 1.1176 1.3716)
			(layers "F.Cu" "F.Mask" "F.Paste")
			(net "P52V_HS1_DV_DT")
		)
	)
	(footprint ""
		(layer "F.Cu")
		(at 40.781478 -63.28156)
		(property "Reference" "R5896"
			(at 0 0 0)
			(layer "F.SilkS")
			(hide yes)
			(effects
				(font
					(size 1.27 1.27)
				)
			)
		)
		(property "Value" ""
			(at 0 0 0)
			(layer "F.Fab")
			(effects
				(font
					(size 1.27 1.27)
				)
			)
		)
		(duplicate_pad_numbers_are_jumpers no)
		(fp_line
			(start -0.7874 -0.4064)
			(end 0.7874 -0.4064)
			(stroke
				(width 0.1524)
				(type default)
			)
			(layer "F.SilkS")
		)
		(fp_line
			(start -0.7874 0.4064)
			(end -0.7874 -0.4064)
			(stroke
				(width 0.1524)
				(type default)
			)
			(layer "F.SilkS")
		)
		(fp_line
			(start 0.7874 -0.4064)
			(end 0.7874 0.4064)
			(stroke
				(width 0.1524)
				(type default)
			)
			(layer "F.SilkS")
		)
		(fp_line
			(start 0.7874 0.4064)
			(end -0.7874 0.4064)
			(stroke
				(width 0.1524)
				(type default)
			)
			(layer "F.SilkS")
		)
		(fp_line
			(start -0.67945 -0.305054)
			(end -0.12065 -0.305054)
			(stroke
				(width 0.1)
				(type default)
			)
			(layer "F.Fab")
		)
		(fp_line
			(start -0.67945 0.3048)
			(end -0.67945 -0.305054)
			(stroke
				(width 0.1)
				(type default)
			)
			(layer "F.Fab")
		)
		(fp_line
			(start -0.12065 -0.305054)
			(end -0.12065 -0.2794)
			(stroke
				(width 0.1)
				(type default)
			)
			(layer "F.Fab")
		)
		(fp_line
			(start -0.12065 -0.2794)
			(end 0.12065 -0.2794)
			(stroke
				(width 0.1)
				(type default)
			)
			(layer "F.Fab")
		)
		(fp_line
			(start -0.12065 0.2794)
			(end -0.12065 0.3048)
			(stroke
				(width 0.1)
				(type default)
			)
			(layer "F.Fab")
		)
		(fp_line
			(start -0.12065 0.3048)
			(end -0.67945 0.3048)
			(stroke
				(width 0.1)
				(type default)
			)
			(layer "F.Fab")
		)
		(fp_line
			(start 0.120396 0.2794)
			(end -0.12065 0.2794)
			(stroke
				(width 0.1)
				(type default)
			)
			(layer "F.Fab")
		)
		(fp_line
			(start 0.120396 0.3048)
			(end 0.120396 0.2794)
			(stroke
				(width 0.1)
				(type default)
			)
			(layer "F.Fab")
		)
		(fp_line
			(start 0.12065 -0.3048)
			(end 0.67945 -0.3048)
			(stroke
				(width 0.1)
				(type default)
			)
			(layer "F.Fab")
		)
		(fp_line
			(start 0.12065 -0.2794)
			(end 0.12065 -0.3048)
			(stroke
				(width 0.1)
				(type default)
			)
			(layer "F.Fab")
		)
		(fp_line
			(start 0.67945 -0.3048)
			(end 0.67945 0.3048)
			(stroke
				(width 0.1)
				(type default)
			)
			(layer "F.Fab")
		)
		(fp_line
			(start 0.67945 0.3048)
			(end 0.120396 0.3048)
			(stroke
				(width 0.1)
				(type default)
			)
			(layer "F.Fab")
		)
		(pad "1" smd rect
			(at -0.40005 0 180)
			(size 0.4572 0.508)
			(layers "F.Cu" "F.Mask" "F.Paste")
			(net "P12V_HPDB")
		)
		(pad "2" smd rect
			(at 0.40005 0 180)
			(size 0.4572 0.508)
			(layers "F.Cu" "F.Mask" "F.Paste")
			(net "P12V_HPDB_0_FB")
		)
	)
	(footprint ""
		(layer "F.Cu")
		(at 163.576 -8.382)
		(property "Reference" "R82"
			(at 0 0 0)
			(layer "F.SilkS")
			(hide yes)
			(effects
				(font
					(size 1.27 1.27)
				)
			)
		)
		(property "Value" ""
			(at 0 0 0)
			(layer "F.Fab")
			(effects
				(font
					(size 1.27 1.27)
				)
			)
		)
		(duplicate_pad_numbers_are_jumpers no)
		(fp_line
			(start -0.7874 -0.4064)
			(end 0.7874 -0.4064)
			(stroke
				(width 0.1524)
				(type default)
			)
			(layer "F.SilkS")
		)
		(fp_line
			(start -0.7874 0.4064)
			(end -0.7874 -0.4064)
			(stroke
				(width 0.1524)
				(type default)
			)
			(layer "F.SilkS")
		)
		(fp_line
			(start 0.7874 -0.4064)
			(end 0.7874 0.4064)
			(stroke
				(width 0.1524)
				(type default)
			)
			(layer "F.SilkS")
		)
		(fp_line
			(start 0.7874 0.4064)
			(end -0.7874 0.4064)
			(stroke
				(width 0.1524)
				(type default)
			)
			(layer "F.SilkS")
		)
		(fp_line
			(start -0.67945 -0.305054)
			(end -0.12065 -0.305054)
			(stroke
				(width 0.1)
				(type default)
			)
			(layer "F.Fab")
		)
		(fp_line
			(start -0.67945 0.3048)
			(end -0.67945 -0.305054)
			(stroke
				(width 0.1)
				(type default)
			)
			(layer "F.Fab")
		)
		(fp_line
			(start -0.12065 -0.305054)
			(end -0.12065 -0.2794)
			(stroke
				(width 0.1)
				(type default)
			)
			(layer "F.Fab")
		)
		(fp_line
			(start -0.12065 -0.2794)
			(end 0.12065 -0.2794)
			(stroke
				(width 0.1)
				(type default)
			)
			(layer "F.Fab")
		)
		(fp_line
			(start -0.12065 0.2794)
			(end -0.12065 0.3048)
			(stroke
				(width 0.1)
				(type default)
			)
			(layer "F.Fab")
		)
		(fp_line
			(start -0.12065 0.3048)
			(end -0.67945 0.3048)
			(stroke
				(width 0.1)
				(type default)
			)
			(layer "F.Fab")
		)
		(fp_line
			(start 0.120396 0.2794)
			(end -0.12065 0.2794)
			(stroke
				(width 0.1)
				(type default)
			)
			(layer "F.Fab")
		)
		(fp_line
			(start 0.120396 0.3048)
			(end 0.120396 0.2794)
			(stroke
				(width 0.1)
				(type default)
			)
			(layer "F.Fab")
		)
		(fp_line
			(start 0.12065 -0.3048)
			(end 0.67945 -0.3048)
			(stroke
				(width 0.1)
				(type default)
			)
			(layer "F.Fab")
		)
		(fp_line
			(start 0.12065 -0.2794)
			(end 0.12065 -0.3048)
			(stroke
				(width 0.1)
				(type default)
			)
			(layer "F.Fab")
		)
		(fp_line
			(start 0.67945 -0.3048)
			(end 0.67945 0.3048)
			(stroke
				(width 0.1)
				(type default)
			)
			(layer "F.Fab")
		)
		(fp_line
			(start 0.67945 0.3048)
			(end 0.120396 0.3048)
			(stroke
				(width 0.1)
				(type default)
			)
			(layer "F.Fab")
		)
		(pad "1" smd rect
			(at -0.40005 0 180)
			(size 0.4572 0.508)
			(layers "F.Cu" "F.Mask" "F.Paste")
			(net "P12V_BRICK")
		)
		(pad "2" smd rect
			(at 0.40005 0 180)
			(size 0.4572 0.508)
			(layers "F.Cu" "F.Mask" "F.Paste")
			(net "P12V_BRICK0_PWRGD")
		)
	)
	(footprint ""
		(layer "F.Cu")
		(at 180.34 -12.192 -90)
		(property "Reference" "PC103"
			(at 0 0 270)
			(layer "F.SilkS")
			(hide yes)
			(effects
				(font
					(size 1.27 1.27)
				)
			)
		)
		(property "Value" ""
			(at 0 0 270)
			(layer "F.Fab")
			(effects
				(font
					(size 1.27 1.27)
				)
			)
		)
		(duplicate_pad_numbers_are_jumpers no)
		(fp_line
			(start -0.7874 0.4064)
			(end -0.7874 -0.4064)
			(stroke
				(width 0.1524)
				(type default)
			)
			(layer "F.SilkS")
		)
		(fp_line
			(start 0.7874 0.4064)
			(end -0.7874 0.4064)
			(stroke
				(width 0.1524)
				(type default)
			)
			(layer "F.SilkS")
		)
		(fp_line
			(start -0.7874 -0.4064)
			(end 0.7874 -0.4064)
			(stroke
				(width 0.1524)
				(type default)
			)
			(layer "F.SilkS")
		)
		(fp_line
			(start 0.7874 -0.4064)
			(end 0.7874 0.4064)
			(stroke
				(width 0.1524)
				(type default)
			)
			(layer "F.SilkS")
		)
		(fp_line
			(start -0.67945 0.3048)
			(end -0.67945 -0.305054)
			(stroke
				(width 0.1)
				(type default)
			)
			(layer "F.Fab")
		)
		(fp_line
			(start -0.12065 0.3048)
			(end -0.67945 0.3048)
			(stroke
				(width 0.1)
				(type default)
			)
			(layer "F.Fab")
		)
		(fp_line
			(start 0.120396 0.3048)
			(end 0.120396 0.2794)
			(stroke
				(width 0.1)
				(type default)
			)
			(layer "F.Fab")
		)
		(fp_line
			(start 0.67945 0.3048)
			(end 0.120396 0.3048)
			(stroke
				(width 0.1)
				(type default)
			)
			(layer "F.Fab")
		)
		(fp_line
			(start -0.12065 0.2794)
			(end -0.12065 0.3048)
			(stroke
				(width 0.1)
				(type default)
			)
			(layer "F.Fab")
		)
		(fp_line
			(start 0.120396 0.2794)
			(end -0.12065 0.2794)
			(stroke
				(width 0.1)
				(type default)
			)
			(layer "F.Fab")
		)
		(fp_line
			(start -0.12065 -0.2794)
			(end 0.12065 -0.2794)
			(stroke
				(width 0.1)
				(type default)
			)
			(layer "F.Fab")
		)
		(fp_line
			(start 0.12065 -0.2794)
			(end 0.12065 -0.3048)
			(stroke
				(width 0.1)
				(type default)
			)
			(layer "F.Fab")
		)
		(fp_line
			(start 0.12065 -0.3048)
			(end 0.67945 -0.3048)
			(stroke
				(width 0.1)
				(type default)
			)
			(layer "F.Fab")
		)
		(fp_line
			(start 0.67945 -0.3048)
			(end 0.67945 0.3048)
			(stroke
				(width 0.1)
				(type default)
			)
			(layer "F.Fab")
		)
		(fp_line
			(start -0.67945 -0.305054)
			(end -0.12065 -0.305054)
			(stroke
				(width 0.1)
				(type default)
			)
			(layer "F.Fab")
		)
		(fp_line
			(start -0.12065 -0.305054)
			(end -0.12065 -0.2794)
			(stroke
				(width 0.1)
				(type default)
			)
			(layer "F.Fab")
		)
		(pad "1" smd circle
			(at -0.40005 0 270)
			(size 0 0)
			(layers "F.Cu" "F.Mask" "F.Paste")
			(net "SW_P3V3_AUX_PH")
		)
		(pad "2" smd circle
			(at 0.40005 0 270)
			(size 0 0)
			(layers "F.Cu" "F.Mask" "F.Paste")
			(net "SW_P3V3_AUX_BT_R")
		)
	)
)
